# S9S_MB_2U (Grand Teton) — schematic netlist excerpt (pin names and nets, part order shuffled) for the footprints in the layout excerpt that follows; sources: Cadence DE-HDL packaged netlist, KiCad conversion of 03242023_DA0F0TMBIJ0_F0T_Motherboard_J_brd_V01_OCP.brd

PR389  Q_RES  1 1% CHIP  pkg 0402LF  page 259 : A = P3V3_AUX_VDRV ; B = P3V3_AUX_VCC
R203  Q_RES  1.5K 1% CHIP  pkg 0402LF  page 122 : A = H_CPU0_MEMHOT_OUT_LVC1_R_N ; B = H_CPU0_MEMHOT_OUT_VT_R_N

(kicad_pcb
	(version 20260206)
	(generator "pcbnew")
	(generator_version "10.0")
	(general
		(thickness 1.6)
		(legacy_teardrops no)
	)
	(paper "A4")
	(title_block
		(title "03242023_DA0F0TMBIJ0_F0T_Motherboard_J_brd_V01_OCP.brd")
		(comment 1 "Grand Teton / footprints 3175-3176 of 6105")
	)
	(layers
		(0 "F.Cu" signal "TOP")
		(4 "In1.Cu" signal "GND")
		(6 "In2.Cu" signal "IN1")
		(8 "In3.Cu" signal "GND1")
		(10 "In4.Cu" signal "IN2")
		(12 "In5.Cu" signal "GND2")
		(14 "In6.Cu" signal "IN3")
		(16 "In7.Cu" signal "GND3")
		(18 "In8.Cu" signal "VCC")
		(20 "In9.Cu" signal "VCC1")
		(22 "In10.Cu" signal "GND4")
		(24 "In11.Cu" signal "IN4")
		(26 "In12.Cu" signal "GND5")
		(28 "In13.Cu" signal "IN5")
		(30 "In14.Cu" signal "GND6")
		(32 "In15.Cu" signal "IN6")
		(34 "In16.Cu" signal "GND7")
		(2 "B.Cu" signal "BOTTOM")
		(9 "F.Adhes" user "F.Adhesive")
		(11 "B.Adhes" user "B.Adhesive")
		(13 "F.Paste" user "Package Geometry/Pastemask Top")
		(15 "B.Paste" user "Package Geometry/Pastemask Bottom")
		(5 "F.SilkS" user "Ref Des/Silkscreen Top")
		(7 "B.SilkS" user "Ref Des/Silkscreen Bottom")
		(1 "F.Mask" user "Board Geometry/Soldermask Top")
		(3 "B.Mask" user "Board Geometry/Soldermask Bottom")
		(17 "Dwgs.User" user "User.Drawings")
		(19 "Cmts.User" user "User.Comments")
		(21 "Eco1.User" user "User.Eco1")
		(23 "Eco2.User" user "User.Eco2")
		(25 "Edge.Cuts" user "Board Geometry/Outline")
		(27 "Margin" user)
		(31 "F.CrtYd" user "Package Geometry/Place Bound Top")
		(29 "B.CrtYd" user "Package Geometry/Place Bound Bottom")
		(35 "F.Fab" user "Ref Des/Assembly Top")
		(33 "B.Fab" user "Ref Des/Assembly Bottom")
	)
	(footprint ""
		(layer "F.Cu")
		(at 443.576964 -72.398128 90)
		(property "Reference" "PR389"
			(at 0 0 90)
			(layer "F.SilkS")
			(hide yes)
			(effects
				(font
					(size 1.27 1.27)
				)
			)
		)
		(property "Value" ""
			(at 0 0 90)
			(layer "F.Fab")
			(effects
				(font
					(size 1.27 1.27)
				)
			)
		)
		(duplicate_pad_numbers_are_jumpers no)
		(fp_line
			(start 0.7874 -0.4064)
			(end 0.7874 0.4064)
			(stroke
				(width 0.1524)
				(type default)
			)
			(layer "F.SilkS")
		)
		(fp_line
			(start -0.7874 -0.4064)
			(end 0.7874 -0.4064)
			(stroke
				(width 0.1524)
				(type default)
			)
			(layer "F.SilkS")
		)
		(fp_line
			(start 0.7874 0.4064)
			(end -0.7874 0.4064)
			(stroke
				(width 0.1524)
				(type default)
			)
			(layer "F.SilkS")
		)
		(fp_line
			(start -0.7874 0.4064)
			(end -0.7874 -0.4064)
			(stroke
				(width 0.1524)
				(type default)
			)
			(layer "F.SilkS")
		)
		(fp_line
			(start -0.12065 -0.305054)
			(end -0.12065 -0.2794)
			(stroke
				(width 0.1)
				(type default)
			)
			(layer "F.Fab")
		)
		(fp_line
			(start -0.67945 -0.305054)
			(end -0.12065 -0.305054)
			(stroke
				(width 0.1)
				(type default)
			)
			(layer "F.Fab")
		)
		(fp_line
			(start 0.67945 -0.3048)
			(end 0.67945 0.3048)
			(stroke
				(width 0.1)
				(type default)
			)
			(layer "F.Fab")
		)
		(fp_line
			(start 0.12065 -0.3048)
			(end 0.67945 -0.3048)
			(stroke
				(width 0.1)
				(type default)
			)
			(layer "F.Fab")
		)
		(fp_line
			(start 0.12065 -0.2794)
			(end 0.12065 -0.3048)
			(stroke
				(width 0.1)
				(type default)
			)
			(layer "F.Fab")
		)
		(fp_line
			(start -0.12065 -0.2794)
			(end 0.12065 -0.2794)
			(stroke
				(width 0.1)
				(type default)
			)
			(layer "F.Fab")
		)
		(fp_line
			(start 0.120396 0.2794)
			(end -0.12065 0.2794)
			(stroke
				(width 0.1)
				(type default)
			)
			(layer "F.Fab")
		)
		(fp_line
			(start -0.12065 0.2794)
			(end -0.12065 0.3048)
			(stroke
				(width 0.1)
				(type default)
			)
			(layer "F.Fab")
		)
		(fp_line
			(start 0.67945 0.3048)
			(end 0.120396 0.3048)
			(stroke
				(width 0.1)
				(type default)
			)
			(layer "F.Fab")
		)
		(fp_line
			(start 0.120396 0.3048)
			(end 0.120396 0.2794)
			(stroke
				(width 0.1)
				(type default)
			)
			(layer "F.Fab")
		)
		(fp_line
			(start -0.12065 0.3048)
			(end -0.67945 0.3048)
			(stroke
				(width 0.1)
				(type default)
			)
			(layer "F.Fab")
		)
		(fp_line
			(start -0.67945 0.3048)
			(end -0.67945 -0.305054)
			(stroke
				(width 0.1)
				(type default)
			)
			(layer "F.Fab")
		)
		(pad "1" smd circle
			(at -0.40005 0 90)
			(size 0 0)
			(layers "F.Cu" "F.Mask" "F.Paste")
			(net "P3V3_AUX_VDRV")
		)
		(pad "2" smd circle
			(at 0.40005 0 90)
			(size 0 0)
			(layers "F.Cu" "F.Mask" "F.Paste")
			(net "P3V3_AUX_VCC")
		)
	)
	(footprint ""
		(layer "F.Cu")
		(at 129.72288 -92.674948 90)
		(property "Reference" "R203"
			(at 0 0 90)
			(layer "F.SilkS")
			(hide yes)
			(effects
				(font
					(size 1.27 1.27)
				)
			)
		)
		(property "Value" ""
			(at 0 0 90)
			(layer "F.Fab")
			(effects
				(font
					(size 1.27 1.27)
				)
			)
		)
		(duplicate_pad_numbers_are_jumpers no)
		(fp_line
			(start 0.7874 -0.4064)
			(end 0.7874 0.4064)
			(stroke
				(width 0.1524)
				(type default)
			)
			(layer "F.SilkS")
		)
		(fp_line
			(start -0.7874 -0.4064)
			(end 0.7874 -0.4064)
			(stroke
				(width 0.1524)
				(type default)
			)
			(layer "F.SilkS")
		)
		(fp_line
			(start 0.7874 0.4064)
			(end -0.7874 0.4064)
			(stroke
				(width 0.1524)
				(type default)
			)
			(layer "F.SilkS")
		)
		(fp_line
			(start -0.7874 0.4064)
			(end -0.7874 -0.4064)
			(stroke
				(width 0.1524)
				(type default)
			)
			(layer "F.SilkS")
		)
		(fp_line
			(start -0.12065 -0.305054)
			(end -0.12065 -0.2794)
			(stroke
				(width 0.1)
				(type default)
			)
			(layer "F.Fab")
		)
		(fp_line
			(start -0.67945 -0.305054)
			(end -0.12065 -0.305054)
			(stroke
				(width 0.1)
				(type default)
			)
			(layer "F.Fab")
		)
		(fp_line
			(start 0.67945 -0.3048)
			(end 0.67945 0.3048)
			(stroke
				(width 0.1)
				(type default)
			)
			(layer "F.Fab")
		)
		(fp_line
			(start 0.12065 -0.3048)
			(end 0.67945 -0.3048)
			(stroke
				(width 0.1)
				(type default)
			)
			(layer "F.Fab")
		)
		(fp_line
			(start 0.12065 -0.2794)
			(end 0.12065 -0.3048)
			(stroke
				(width 0.1)
				(type default)
			)
			(layer "F.Fab")
		)
		(fp_line
			(start -0.12065 -0.2794)
			(end 0.12065 -0.2794)
			(stroke
				(width 0.1)
				(type default)
			)
			(layer "F.Fab")
		)
		(fp_line
			(start 0.120396 0.2794)
			(end -0.12065 0.2794)
			(stroke
				(width 0.1)
				(type default)
			)
			(layer "F.Fab")
		)
		(fp_line
			(start -0.12065 0.2794)
			(end -0.12065 0.3048)
			(stroke
				(width 0.1)
				(type default)
			)
			(layer "F.Fab")
		)
		(fp_line
			(start 0.67945 0.3048)
			(end 0.120396 0.3048)
			(stroke
				(width 0.1)
				(type default)
			)
			(layer "F.Fab")
		)
		(fp_line
			(start 0.120396 0.3048)
			(end 0.120396 0.2794)
			(stroke
				(width 0.1)
				(type default)
			)
			(layer "F.Fab")
		)
		(fp_line
			(start -0.12065 0.3048)
			(end -0.67945 0.3048)
			(stroke
				(width 0.1)
				(type default)
			)
			(layer "F.Fab")
		)
		(fp_line
			(start -0.67945 0.3048)
			(end -0.67945 -0.305054)
			(stroke
				(width 0.1)
				(type default)
			)
			(layer "F.Fab")
		)
		(pad "1" smd circle
			(at -0.40005 0 90)
			(size 0 0)
			(layers "F.Cu" "F.Mask" "F.Paste")
			(net "H_CPU0_MEMHOT_OUT_LVC1_R_N")
		)
		(pad "2" smd circle
			(at 0.40005 0 90)
			(size 0 0)
			(layers "F.Cu" "F.Mask" "F.Paste")
			(net "H_CPU0_MEMHOT_OUT_VT_R_N")
		)
	)
)
